# T6G (Grand Teton) — schematic netlist excerpt (pin names and nets, part order shuffled) for the footprints in the layout excerpt that follows; sources: Cadence DE-HDL packaged netlist, KiCad conversion of 04192023_DAF0TMB3IC0_F0TG_MB_C_brd_V02_OCP.brd

R4476  Q_RES  10K 1% CHIP  pkg 0402LF  page 182 : A = P3V3_AUX ; B = FM_9ZXL045_P0_DEV_EN
PC173_IOP0_4  Q_CAP  2.2UF 10V 10% X6S  pkg C0402  page 206 : A = PVDDCR_CPU1_P0_PVCC ; B = GND

(kicad_pcb
	(version 20260206)
	(generator "pcbnew")
	(generator_version "10.0")
	(general
		(thickness 1.6)
		(legacy_teardrops no)
	)
	(paper "A4")
	(title_block
		(title "04192023_DAF0TMB3IC0_F0TG_MB_C_brd_V02_OCP.brd")
		(comment 1 "Grand Teton / footprints 1781-1782 of 8354")
	)
	(layers
		(0 "F.Cu" signal "TOP")
		(4 "In1.Cu" signal "GND")
		(6 "In2.Cu" signal "IN1")
		(8 "In3.Cu" signal "GND1")
		(10 "In4.Cu" signal "IN2")
		(12 "In5.Cu" signal "GND2")
		(14 "In6.Cu" signal "IN3")
		(16 "In7.Cu" signal "GND3")
		(18 "In8.Cu" signal "VCC")
		(20 "In9.Cu" signal "VCC1")
		(22 "In10.Cu" signal "GND4")
		(24 "In11.Cu" signal "IN4")
		(26 "In12.Cu" signal "GND5")
		(28 "In13.Cu" signal "IN5")
		(30 "In14.Cu" signal "GND6")
		(32 "In15.Cu" signal "IN6")
		(34 "In16.Cu" signal "GND7")
		(2 "B.Cu" signal "BOTTOM")
		(9 "F.Adhes" user "F.Adhesive")
		(11 "B.Adhes" user "B.Adhesive")
		(13 "F.Paste" user "Package Geometry/Pastemask Top")
		(15 "B.Paste" user "Package Geometry/Pastemask Bottom")
		(5 "F.SilkS" user "Ref Des/Silkscreen Top")
		(7 "B.SilkS" user "Ref Des/Silkscreen Bottom")
		(1 "F.Mask" user "Board Geometry/Soldermask Top")
		(3 "B.Mask" user "Board Geometry/Soldermask Bottom")
		(17 "Dwgs.User" user "User.Drawings")
		(19 "Cmts.User" user "User.Comments")
		(21 "Eco1.User" user "User.Eco1")
		(23 "Eco2.User" user "User.Eco2")
		(25 "Edge.Cuts" user "Board Geometry/Outline")
		(27 "Margin" user)
		(31 "F.CrtYd" user "Package Geometry/Place Bound Top")
		(29 "B.CrtYd" user "Package Geometry/Place Bound Bottom")
		(35 "F.Fab" user "Ref Des/Assembly Top")
		(33 "B.Fab" user "Ref Des/Assembly Bottom")
	)
	(footprint ""
		(layer "F.Cu")
		(at 281.686 -423.418 -90)
		(property "Reference" "R4476"
			(at 0 0 270)
			(layer "F.SilkS")
			(hide yes)
			(effects
				(font
					(size 1.27 1.27)
				)
			)
		)
		(property "Value" ""
			(at 0 0 270)
			(layer "F.Fab")
			(effects
				(font
					(size 1.27 1.27)
				)
			)
		)
		(duplicate_pad_numbers_are_jumpers no)
		(fp_line
			(start -0.7874 0.4064)
			(end -0.7874 -0.4064)
			(stroke
				(width 0.1524)
				(type default)
			)
			(layer "F.SilkS")
		)
		(fp_line
			(start 0.7874 0.4064)
			(end -0.7874 0.4064)
			(stroke
				(width 0.1524)
				(type default)
			)
			(layer "F.SilkS")
		)
		(fp_line
			(start -0.7874 -0.4064)
			(end 0.7874 -0.4064)
			(stroke
				(width 0.1524)
				(type default)
			)
			(layer "F.SilkS")
		)
		(fp_line
			(start 0.7874 -0.4064)
			(end 0.7874 0.4064)
			(stroke
				(width 0.1524)
				(type default)
			)
			(layer "F.SilkS")
		)
		(fp_line
			(start -0.67945 0.3048)
			(end -0.67945 -0.305054)
			(stroke
				(width 0.1)
				(type default)
			)
			(layer "F.Fab")
		)
		(fp_line
			(start -0.12065 0.3048)
			(end -0.67945 0.3048)
			(stroke
				(width 0.1)
				(type default)
			)
			(layer "F.Fab")
		)
		(fp_line
			(start 0.120396 0.3048)
			(end 0.120396 0.2794)
			(stroke
				(width 0.1)
				(type default)
			)
			(layer "F.Fab")
		)
		(fp_line
			(start 0.67945 0.3048)
			(end 0.120396 0.3048)
			(stroke
				(width 0.1)
				(type default)
			)
			(layer "F.Fab")
		)
		(fp_line
			(start -0.12065 0.2794)
			(end -0.12065 0.3048)
			(stroke
				(width 0.1)
				(type default)
			)
			(layer "F.Fab")
		)
		(fp_line
			(start 0.120396 0.2794)
			(end -0.12065 0.2794)
			(stroke
				(width 0.1)
				(type default)
			)
			(layer "F.Fab")
		)
		(fp_line
			(start -0.12065 -0.2794)
			(end 0.12065 -0.2794)
			(stroke
				(width 0.1)
				(type default)
			)
			(layer "F.Fab")
		)
		(fp_line
			(start 0.12065 -0.2794)
			(end 0.12065 -0.3048)
			(stroke
				(width 0.1)
				(type default)
			)
			(layer "F.Fab")
		)
		(fp_line
			(start 0.12065 -0.3048)
			(end 0.67945 -0.3048)
			(stroke
				(width 0.1)
				(type default)
			)
			(layer "F.Fab")
		)
		(fp_line
			(start 0.67945 -0.3048)
			(end 0.67945 0.3048)
			(stroke
				(width 0.1)
				(type default)
			)
			(layer "F.Fab")
		)
		(fp_line
			(start -0.67945 -0.305054)
			(end -0.12065 -0.305054)
			(stroke
				(width 0.1)
				(type default)
			)
			(layer "F.Fab")
		)
		(fp_line
			(start -0.12065 -0.305054)
			(end -0.12065 -0.2794)
			(stroke
				(width 0.1)
				(type default)
			)
			(layer "F.Fab")
		)
		(pad "1" smd circle
			(at -0.40005 0 270)
			(size 0 0)
			(layers "F.Cu" "F.Mask" "F.Paste")
			(net "P3V3_AUX")
		)
		(pad "2" smd circle
			(at 0.40005 0 270)
			(size 0 0)
			(layers "F.Cu" "F.Mask" "F.Paste")
			(net "FM_9ZXL045_P0_DEV_EN")
		)
	)
	(footprint ""
		(layer "F.Cu")
		(at 271.739106 -346.714572 -90)
		(property "Reference" "PC173_IOP0_4"
			(at 0 0 270)
			(layer "F.SilkS")
			(hide yes)
			(effects
				(font
					(size 1.27 1.27)
				)
			)
		)
		(property "Value" ""
			(at 0 0 270)
			(layer "F.Fab")
			(effects
				(font
					(size 1.27 1.27)
				)
			)
		)
		(duplicate_pad_numbers_are_jumpers no)
		(fp_line
			(start -0.7874 0.4064)
			(end -0.7874 -0.4064)
			(stroke
				(width 0.1524)
				(type default)
			)
			(layer "F.SilkS")
		)
		(fp_line
			(start 0.7874 0.4064)
			(end -0.7874 0.4064)
			(stroke
				(width 0.1524)
				(type default)
			)
			(layer "F.SilkS")
		)
		(fp_line
			(start -0.7874 -0.4064)
			(end 0.7874 -0.4064)
			(stroke
				(width 0.1524)
				(type default)
			)
			(layer "F.SilkS")
		)
		(fp_line
			(start 0.7874 -0.4064)
			(end 0.7874 0.4064)
			(stroke
				(width 0.1524)
				(type default)
			)
			(layer "F.SilkS")
		)
		(fp_line
			(start -0.67945 0.3048)
			(end -0.67945 -0.305054)
			(stroke
				(width 0.1)
				(type default)
			)
			(layer "F.Fab")
		)
		(fp_line
			(start -0.12065 0.3048)
			(end -0.67945 0.3048)
			(stroke
				(width 0.1)
				(type default)
			)
			(layer "F.Fab")
		)
		(fp_line
			(start 0.120396 0.3048)
			(end 0.120396 0.2794)
			(stroke
				(width 0.1)
				(type default)
			)
			(layer "F.Fab")
		)
		(fp_line
			(start 0.67945 0.3048)
			(end 0.120396 0.3048)
			(stroke
				(width 0.1)
				(type default)
			)
			(layer "F.Fab")
		)
		(fp_line
			(start -0.12065 0.2794)
			(end -0.12065 0.3048)
			(stroke
				(width 0.1)
				(type default)
			)
			(layer "F.Fab")
		)
		(fp_line
			(start 0.120396 0.2794)
			(end -0.12065 0.2794)
			(stroke
				(width 0.1)
				(type default)
			)
			(layer "F.Fab")
		)
		(fp_line
			(start -0.12065 -0.2794)
			(end 0.12065 -0.2794)
			(stroke
				(width 0.1)
				(type default)
			)
			(layer "F.Fab")
		)
		(fp_line
			(start 0.12065 -0.2794)
			(end 0.12065 -0.3048)
			(stroke
				(width 0.1)
				(type default)
			)
			(layer "F.Fab")
		)
		(fp_line
			(start 0.12065 -0.3048)
			(end 0.67945 -0.3048)
			(stroke
				(width 0.1)
				(type default)
			)
			(layer "F.Fab")
		)
		(fp_line
			(start 0.67945 -0.3048)
			(end 0.67945 0.3048)
			(stroke
				(width 0.1)
				(type default)
			)
			(layer "F.Fab")
		)
		(fp_line
			(start -0.67945 -0.305054)
			(end -0.12065 -0.305054)
			(stroke
				(width 0.1)
				(type default)
			)
			(layer "F.Fab")
		)
		(fp_line
			(start -0.12065 -0.305054)
			(end -0.12065 -0.2794)
			(stroke
				(width 0.1)
				(type default)
			)
			(layer "F.Fab")
		)
		(pad "1" smd circle
			(at -0.40005 0 270)
			(size 0 0)
			(layers "F.Cu" "F.Mask" "F.Paste")
			(net "PVDDCR_CPU1_P0_PVCC")
		)
		(pad "2" smd circle
			(at 0.40005 0 270)
			(size 0 0)
			(layers "F.Cu" "F.Mask" "F.Paste")
			(net "GND")
		)
	)
)
